(kicad_pcb
	(version 20260206)
	(generator "pcbnew")
	(generator_version "10.0")
	(general
		(thickness 1.6)
		(legacy_teardrops no)
	)
	(paper "A4")
	(title_block
		(title "03242023_DA0F0TMBIJ0_F0T_Motherboard_J_brd_V01_OCP.brd")
		(comment 1 "Grand Teton / footprints 5750-5755 of 6105")
	)
	(layers
		(0 "F.Cu" signal "TOP")
		(4 "In1.Cu" signal "GND")
		(6 "In2.Cu" signal "IN1")
		(8 "In3.Cu" signal "GND1")
		(10 "In4.Cu" signal "IN2")
		(12 "In5.Cu" signal "GND2")
		(14 "In6.Cu" signal "IN3")
		(16 "In7.Cu" signal "GND3")
		(18 "In8.Cu" signal "VCC")
		(20 "In9.Cu" signal "VCC1")
		(22 "In10.Cu" signal "GND4")
		(24 "In11.Cu" signal "IN4")
		(26 "In12.Cu" signal "GND5")
		(28 "In13.Cu" signal "IN5")
		(30 "In14.Cu" signal "GND6")
		(32 "In15.Cu" signal "IN6")
		(34 "In16.Cu" signal "GND7")
		(2 "B.Cu" signal "BOTTOM")
		(9 "F.Adhes" user "F.Adhesive")
		(11 "B.Adhes" user "B.Adhesive")
		(13 "F.Paste" user "Package Geometry/Pastemask Top")
		(15 "B.Paste" user "Package Geometry/Pastemask Bottom")
		(5 "F.SilkS" user "Ref Des/Silkscreen Top")
		(7 "B.SilkS" user "Ref Des/Silkscreen Bottom")
		(1 "F.Mask" user "Board Geometry/Soldermask Top")
		(3 "B.Mask" user "Board Geometry/Soldermask Bottom")
		(17 "Dwgs.User" user "User.Drawings")
		(19 "Cmts.User" user "User.Comments")
		(21 "Eco1.User" user "User.Eco1")
		(23 "Eco2.User" user "User.Eco2")
		(25 "Edge.Cuts" user "Board Geometry/Outline")
		(27 "Margin" user)
		(31 "F.CrtYd" user "Package Geometry/Place Bound Top")
		(29 "B.CrtYd" user "Package Geometry/Place Bound Bottom")
		(35 "F.Fab" user "Ref Des/Assembly Top")
		(33 "B.Fab" user "Ref Des/Assembly Bottom")
	)
	(footprint ""
		(layer "B.Cu")
		(at 139.346686 -9.362948 90)
		(property "Reference" "R4809"
			(at 0 0 90)
			(layer "B.SilkS")
			(hide yes)
			(effects
				(font
					(size 1.27 1.27)
				)
				(justify mirror)
			)
		)
		(property "Value" ""
			(at 0 0 90)
			(layer "B.Fab")
			(effects
				(font
					(size 1.27 1.27)
				)
				(justify mirror)
			)
		)
		(duplicate_pad_numbers_are_jumpers no)
		(fp_line
			(start 0.7874 -0.4064)
			(end -0.7874 -0.4064)
			(stroke
				(width 0.1524)
				(type default)
			)
			(layer "B.SilkS")
		)
		(fp_line
			(start -0.7874 -0.4064)
			(end -0.7874 0.4064)
			(stroke
				(width 0.1524)
				(type default)
			)
			(layer "B.SilkS")
		)
		(fp_line
			(start 0.7874 0.4064)
			(end 0.7874 -0.4064)
			(stroke
				(width 0.1524)
				(type default)
			)
			(layer "B.SilkS")
		)
		(fp_line
			(start -0.7874 0.4064)
			(end 0.7874 0.4064)
			(stroke
				(width 0.1524)
				(type default)
			)
			(layer "B.SilkS")
		)
		(fp_line
			(start 0.67945 -0.305054)
			(end 0.12065 -0.305054)
			(stroke
				(width 0.1)
				(type default)
			)
			(layer "B.Fab")
		)
		(fp_line
			(start 0.12065 -0.305054)
			(end 0.12065 -0.2794)
			(stroke
				(width 0.1)
				(type default)
			)
			(layer "B.Fab")
		)
		(fp_line
			(start -0.12065 -0.3048)
			(end -0.67945 -0.3048)
			(stroke
				(width 0.1)
				(type default)
			)
			(layer "B.Fab")
		)
		(fp_line
			(start -0.67945 -0.3048)
			(end -0.67945 0.3048)
			(stroke
				(width 0.1)
				(type default)
			)
			(layer "B.Fab")
		)
		(fp_line
			(start 0.12065 -0.2794)
			(end -0.12065 -0.2794)
			(stroke
				(width 0.1)
				(type default)
			)
			(layer "B.Fab")
		)
		(fp_line
			(start -0.12065 -0.2794)
			(end -0.12065 -0.3048)
			(stroke
				(width 0.1)
				(type default)
			)
			(layer "B.Fab")
		)
		(fp_line
			(start 0.12065 0.2794)
			(end 0.12065 0.3048)
			(stroke
				(width 0.1)
				(type default)
			)
			(layer "B.Fab")
		)
		(fp_line
			(start -0.120396 0.2794)
			(end 0.12065 0.2794)
			(stroke
				(width 0.1)
				(type default)
			)
			(layer "B.Fab")
		)
		(fp_line
			(start 0.67945 0.3048)
			(end 0.67945 -0.305054)
			(stroke
				(width 0.1)
				(type default)
			)
			(layer "B.Fab")
		)
		(fp_line
			(start 0.12065 0.3048)
			(end 0.67945 0.3048)
			(stroke
				(width 0.1)
				(type default)
			)
			(layer "B.Fab")
		)
		(fp_line
			(start -0.120396 0.3048)
			(end -0.120396 0.2794)
			(stroke
				(width 0.1)
				(type default)
			)
			(layer "B.Fab")
		)
		(fp_line
			(start -0.67945 0.3048)
			(end -0.120396 0.3048)
			(stroke
				(width 0.1)
				(type default)
			)
			(layer "B.Fab")
		)
		(pad "1" smd circle
			(at 0.40005 0 270)
			(size 0 0)
			(layers "B.Cu" "B.Mask" "B.Paste")
			(net "FM_BMC_INTRUDER_N")
		)
		(pad "2" smd circle
			(at -0.40005 0 270)
			(size 0 0)
			(layers "B.Cu" "B.Mask" "B.Paste")
			(net "GND")
		)
	)
	(footprint ""
		(layer "B.Cu")
		(at 169.66692 -52.415948 180)
		(property "Reference" "C1924"
			(at 0 0 0)
			(layer "B.SilkS")
			(hide yes)
			(effects
				(font
					(size 1.27 1.27)
				)
				(justify mirror)
			)
		)
		(property "Value" ""
			(at 0 0 0)
			(layer "B.Fab")
			(effects
				(font
					(size 1.27 1.27)
				)
				(justify mirror)
			)
		)
		(duplicate_pad_numbers_are_jumpers no)
		(fp_line
			(start 0.7874 0.4064)
			(end 0.7874 -0.4064)
			(stroke
				(width 0.1524)
				(type default)
			)
			(layer "B.SilkS")
		)
		(fp_line
			(start 0.7874 -0.4064)
			(end -0.7874 -0.4064)
			(stroke
				(width 0.1524)
				(type default)
			)
			(layer "B.SilkS")
		)
		(fp_line
			(start -0.7874 0.4064)
			(end 0.7874 0.4064)
			(stroke
				(width 0.1524)
				(type default)
			)
			(layer "B.SilkS")
		)
		(fp_line
			(start -0.7874 -0.4064)
			(end -0.7874 0.4064)
			(stroke
				(width 0.1524)
				(type default)
			)
			(layer "B.SilkS")
		)
		(fp_line
			(start 0.67945 0.3048)
			(end 0.67945 -0.305054)
			(stroke
				(width 0.1)
				(type default)
			)
			(layer "B.Fab")
		)
		(fp_line
			(start 0.67945 -0.305054)
			(end 0.12065 -0.305054)
			(stroke
				(width 0.1)
				(type default)
			)
			(layer "B.Fab")
		)
		(fp_line
			(start 0.12065 0.3048)
			(end 0.67945 0.3048)
			(stroke
				(width 0.1)
				(type default)
			)
			(layer "B.Fab")
		)
		(fp_line
			(start 0.12065 0.2794)
			(end 0.12065 0.3048)
			(stroke
				(width 0.1)
				(type default)
			)
			(layer "B.Fab")
		)
		(fp_line
			(start 0.12065 -0.2794)
			(end -0.12065 -0.2794)
			(stroke
				(width 0.1)
				(type default)
			)
			(layer "B.Fab")
		)
		(fp_line
			(start 0.12065 -0.305054)
			(end 0.12065 -0.2794)
			(stroke
				(width 0.1)
				(type default)
			)
			(layer "B.Fab")
		)
		(fp_line
			(start -0.120396 0.3048)
			(end -0.120396 0.2794)
			(stroke
				(width 0.1)
				(type default)
			)
			(layer "B.Fab")
		)
		(fp_line
			(start -0.120396 0.2794)
			(end 0.12065 0.2794)
			(stroke
				(width 0.1)
				(type default)
			)
			(layer "B.Fab")
		)
		(fp_line
			(start -0.12065 -0.2794)
			(end -0.12065 -0.3048)
			(stroke
				(width 0.1)
				(type default)
			)
			(layer "B.Fab")
		)
		(fp_line
			(start -0.12065 -0.3048)
			(end -0.67945 -0.3048)
			(stroke
				(width 0.1)
				(type default)
			)
			(layer "B.Fab")
		)
		(fp_line
			(start -0.67945 0.3048)
			(end -0.120396 0.3048)
			(stroke
				(width 0.1)
				(type default)
			)
			(layer "B.Fab")
		)
		(fp_line
			(start -0.67945 -0.3048)
			(end -0.67945 0.3048)
			(stroke
				(width 0.1)
				(type default)
			)
			(layer "B.Fab")
		)
		(pad "1" smd circle
			(at 0.40005 0)
			(size 0 0)
			(layers "B.Cu" "B.Mask" "B.Paste")
			(net "P3V3_M2_0")
		)
		(pad "2" smd circle
			(at -0.40005 0)
			(size 0 0)
			(layers "B.Cu" "B.Mask" "B.Paste")
			(net "GND")
		)
	)
	(footprint ""
		(layer "B.Cu")
		(at 120.26392 -237.709456 90)
		(property "Reference" "C465"
			(at 0 0 90)
			(layer "B.SilkS")
			(hide yes)
			(effects
				(font
					(size 1.27 1.27)
				)
				(justify mirror)
			)
		)
		(property "Value" ""
			(at 0 0 90)
			(layer "B.Fab")
			(effects
				(font
					(size 1.27 1.27)
				)
				(justify mirror)
			)
		)
		(duplicate_pad_numbers_are_jumpers no)
		(fp_line
			(start 1.2954 -0.5842)
			(end -1.2954 -0.5842)
			(stroke
				(width 0.1524)
				(type default)
			)
			(layer "B.SilkS")
		)
		(fp_line
			(start 0 -0.5842)
			(end 0 0.5842)
			(stroke
				(width 0.1524)
				(type default)
			)
			(layer "B.SilkS")
		)
		(fp_line
			(start -1.2954 -0.5842)
			(end -1.2954 0.5842)
			(stroke
				(width 0.1524)
				(type default)
			)
			(layer "B.SilkS")
		)
		(fp_line
			(start 1.2954 0.5842)
			(end 1.2954 -0.5842)
			(stroke
				(width 0.1524)
				(type default)
			)
			(layer "B.SilkS")
		)
		(fp_line
			(start -1.2954 0.5842)
			(end 1.2954 0.5842)
			(stroke
				(width 0.1524)
				(type default)
			)
			(layer "B.SilkS")
		)
		(fp_line
			(start 0.8636 -0.4572)
			(end -0.8636 -0.4572)
			(stroke
				(width 0.1)
				(type default)
			)
			(layer "B.Fab")
		)
		(fp_line
			(start -0.8636 -0.4572)
			(end -0.8636 -0.4064)
			(stroke
				(width 0.1)
				(type default)
			)
			(layer "B.Fab")
		)
		(fp_line
			(start 1.1938 -0.4064)
			(end 0.8636 -0.4064)
			(stroke
				(width 0.1)
				(type default)
			)
			(layer "B.Fab")
		)
		(fp_line
			(start 0.8636 -0.4064)
			(end 0.8636 -0.4572)
			(stroke
				(width 0.1)
				(type default)
			)
			(layer "B.Fab")
		)
		(fp_line
			(start -0.8636 -0.4064)
			(end -1.1938 -0.4064)
			(stroke
				(width 0.1)
				(type default)
			)
			(layer "B.Fab")
		)
		(fp_line
			(start -1.1938 -0.4064)
			(end -1.1938 0.4064)
			(stroke
				(width 0.1)
				(type default)
			)
			(layer "B.Fab")
		)
		(fp_line
			(start 1.1938 0.4064)
			(end 1.1938 -0.4064)
			(stroke
				(width 0.1)
				(type default)
			)
			(layer "B.Fab")
		)
		(fp_line
			(start 0.8636 0.4064)
			(end 1.1938 0.4064)
			(stroke
				(width 0.1)
				(type default)
			)
			(layer "B.Fab")
		)
		(fp_line
			(start -0.8636 0.4064)
			(end -0.8636 0.4572)
			(stroke
				(width 0.1)
				(type default)
			)
			(layer "B.Fab")
		)
		(fp_line
			(start -1.1938 0.4064)
			(end -0.8636 0.4064)
			(stroke
				(width 0.1)
				(type default)
			)
			(layer "B.Fab")
		)
		(fp_line
			(start 0.8636 0.4572)
			(end 0.8636 0.4064)
			(stroke
				(width 0.1)
				(type default)
			)
			(layer "B.Fab")
		)
		(fp_line
			(start -0.8636 0.4572)
			(end 0.8636 0.4572)
			(stroke
				(width 0.1)
				(type default)
			)
			(layer "B.Fab")
		)
		(pad "1" smd rect
			(at 0.7366 0)
			(size 0.7112 0.8128)
			(layers "B.Cu" "B.Mask" "B.Paste")
			(net "PVCCFA_EHV_FIVRA_CPU1")
		)
		(pad "2" smd rect
			(at -0.7366 0)
			(size 0.7112 0.8128)
			(layers "B.Cu" "B.Mask" "B.Paste")
			(net "GND")
		)
	)
	(footprint ""
		(layer "B.Cu")
		(at 353.0219 -58.458608)
		(property "Reference" "L10"
			(at 0 0 0)
			(layer "B.SilkS")
			(hide yes)
			(effects
				(font
					(size 1.27 1.27)
				)
				(justify mirror)
			)
		)
		(property "Value" ""
			(at 0 0 0)
			(layer "B.Fab")
			(effects
				(font
					(size 1.27 1.27)
				)
				(justify mirror)
			)
		)
		(duplicate_pad_numbers_are_jumpers no)
		(fp_line
			(start -1.27 0.5842)
			(end -1.27 -0.5842)
			(stroke
				(width 0.1524)
				(type default)
			)
			(layer "B.SilkS")
		)
		(fp_line
			(start -1.27 0.5842)
			(end 1.27 0.5842)
			(stroke
				(width 0.1524)
				(type default)
			)
			(layer "B.SilkS")
		)
		(fp_line
			(start -0.127 0.5842)
			(end -0.127 -0.5842)
			(stroke
				(width 0.1524)
				(type default)
			)
			(layer "B.SilkS")
		)
		(fp_line
			(start 0.127 0.5842)
			(end 0.127 -0.5842)
			(stroke
				(width 0.1524)
				(type default)
			)
			(layer "B.SilkS")
		)
		(fp_line
			(start 1.27 -0.5842)
			(end -1.27 -0.5842)
			(stroke
				(width 0.1524)
				(type default)
			)
			(layer "B.SilkS")
		)
		(fp_line
			(start 1.27 -0.5588)
			(end 1.27 -0.5842)
			(stroke
				(width 0.1524)
				(type default)
			)
			(layer "B.SilkS")
		)
		(fp_line
			(start 1.27 0.5842)
			(end 1.27 -0.5842)
			(stroke
				(width 0.1524)
				(type default)
			)
			(layer "B.SilkS")
		)
		(fp_line
			(start -1.1938 -0.406654)
			(end -1.1938 0.4064)
			(stroke
				(width 0.1)
				(type default)
			)
			(layer "B.Fab")
		)
		(fp_line
			(start -1.1938 0.4064)
			(end -0.9144 0.4064)
			(stroke
				(width 0.1)
				(type default)
			)
			(layer "B.Fab")
		)
		(fp_line
			(start -0.9144 -0.508)
			(end -0.9144 -0.406654)
			(stroke
				(width 0.1)
				(type default)
			)
			(layer "B.Fab")
		)
		(fp_line
			(start -0.9144 -0.406654)
			(end -1.1938 -0.406654)
			(stroke
				(width 0.1)
				(type default)
			)
			(layer "B.Fab")
		)
		(fp_line
			(start -0.9144 0.4064)
			(end -0.9144 0.508)
			(stroke
				(width 0.1)
				(type default)
			)
			(layer "B.Fab")
		)
		(fp_line
			(start -0.9144 0.508)
			(end 0.9144 0.508)
			(stroke
				(width 0.1)
				(type default)
			)
			(layer "B.Fab")
		)
		(fp_line
			(start 0.9144 -0.508)
			(end -0.9144 -0.508)
			(stroke
				(width 0.1)
				(type default)
			)
			(layer "B.Fab")
		)
		(fp_line
			(start 0.9144 -0.406654)
			(end 0.9144 -0.508)
			(stroke
				(width 0.1)
				(type default)
			)
			(layer "B.Fab")
		)
		(fp_line
			(start 0.9144 0.406654)
			(end 1.194308 0.406654)
			(stroke
				(width 0.1)
				(type default)
			)
			(layer "B.Fab")
		)
		(fp_line
			(start 0.9144 0.508)
			(end 0.9144 0.406654)
			(stroke
				(width 0.1)
				(type default)
			)
			(layer "B.Fab")
		)
		(fp_line
			(start 1.194308 -0.406654)
			(end 0.9144 -0.406654)
			(stroke
				(width 0.1)
				(type default)
			)
			(layer "B.Fab")
		)
		(fp_line
			(start 1.194308 0.406654)
			(end 1.194308 -0.406654)
			(stroke
				(width 0.1)
				(type default)
			)
			(layer "B.Fab")
		)
		(pad "1" smd rect
			(at 0.7366 0 270)
			(size 0.7112 0.8128)
			(layers "B.Cu" "B.Mask" "B.Paste")
			(net "P1V8_PCH_AUX")
		)
		(pad "2" smd rect
			(at -0.7366 0 270)
			(size 0.7112 0.8128)
			(layers "B.Cu" "B.Mask" "B.Paste")
			(net "P1V8_PCH_PLL_AUX")
		)
	)
	(footprint ""
		(layer "B.Cu")
		(at 170.433746 -321.554856 -90)
		(property "Reference" "C95"
			(at 0 0 90)
			(layer "B.SilkS")
			(hide yes)
			(effects
				(font
					(size 1.27 1.27)
				)
				(justify mirror)
			)
		)
		(property "Value" ""
			(at 0 0 90)
			(layer "B.Fab")
			(effects
				(font
					(size 1.27 1.27)
				)
				(justify mirror)
			)
		)
		(duplicate_pad_numbers_are_jumpers no)
		(fp_line
			(start -1.524 0.762)
			(end 1.524 0.762)
			(stroke
				(width 0.1524)
				(type default)
			)
			(layer "B.SilkS")
		)
		(fp_line
			(start 1.524 0.762)
			(end 1.524 -0.762)
			(stroke
				(width 0.1524)
				(type default)
			)
			(layer "B.SilkS")
		)
		(fp_line
			(start -1.524 -0.762)
			(end -1.524 0.762)
			(stroke
				(width 0.1524)
				(type default)
			)
			(layer "B.SilkS")
		)
		(fp_line
			(start 1.524 -0.762)
			(end -1.524 -0.762)
			(stroke
				(width 0.1524)
				(type default)
			)
			(layer "B.SilkS")
		)
		(fp_line
			(start -1.1049 0.724916)
			(end -1.1049 -0.724916)
			(stroke
				(width 0.1)
				(type default)
			)
			(layer "B.Fab")
		)
		(fp_line
			(start 1.1049 0.724916)
			(end -1.1049 0.724916)
			(stroke
				(width 0.1)
				(type default)
			)
			(layer "B.Fab")
		)
		(fp_line
			(start -1.1049 -0.724916)
			(end 1.1049 -0.724916)
			(stroke
				(width 0.1)
				(type default)
			)
			(layer "B.Fab")
		)
		(fp_line
			(start 1.1049 -0.724916)
			(end 1.1049 0.724916)
			(stroke
				(width 0.1)
				(type default)
			)
			(layer "B.Fab")
		)
		(pad "1" smd rect
			(at 0.889 0 270)
			(size 1.016 1.27)
			(layers "B.Cu" "B.Mask" "B.Paste")
			(net "P12V_S3_AUX_CPU1_NVDIMM")
		)
		(pad "2" smd rect
			(at -0.889 0 270)
			(size 1.016 1.27)
			(layers "B.Cu" "B.Mask" "B.Paste")
			(net "GND")
		)
	)
	(footprint ""
		(layer "B.Cu")
		(at 203.04506 -78.247748 180)
		(property "Reference" "R3244"
			(at 0 0 0)
			(layer "B.SilkS")
			(hide yes)
			(effects
				(font
					(size 1.27 1.27)
				)
				(justify mirror)
			)
		)
		(property "Value" ""
			(at 0 0 0)
			(layer "B.Fab")
			(effects
				(font
					(size 1.27 1.27)
				)
				(justify mirror)
			)
		)
		(duplicate_pad_numbers_are_jumpers no)
		(fp_line
			(start 0.7874 0.4064)
			(end 0.7874 -0.4064)
			(stroke
				(width 0.1524)
				(type default)
			)
			(layer "B.SilkS")
		)
		(fp_line
			(start 0.7874 -0.4064)
			(end -0.7874 -0.4064)
			(stroke
				(width 0.1524)
				(type default)
			)
			(layer "B.SilkS")
		)
		(fp_line
			(start -0.7874 0.4064)
			(end 0.7874 0.4064)
			(stroke
				(width 0.1524)
				(type default)
			)
			(layer "B.SilkS")
		)
		(fp_line
			(start -0.7874 -0.4064)
			(end -0.7874 0.4064)
			(stroke
				(width 0.1524)
				(type default)
			)
			(layer "B.SilkS")
		)
		(fp_line
			(start 0.67945 0.3048)
			(end 0.67945 -0.305054)
			(stroke
				(width 0.1)
				(type default)
			)
			(layer "B.Fab")
		)
		(fp_line
			(start 0.67945 -0.305054)
			(end 0.12065 -0.305054)
			(stroke
				(width 0.1)
				(type default)
			)
			(layer "B.Fab")
		)
		(fp_line
			(start 0.12065 0.3048)
			(end 0.67945 0.3048)
			(stroke
				(width 0.1)
				(type default)
			)
			(layer "B.Fab")
		)
		(fp_line
			(start 0.12065 0.2794)
			(end 0.12065 0.3048)
			(stroke
				(width 0.1)
				(type default)
			)
			(layer "B.Fab")
		)
		(fp_line
			(start 0.12065 -0.2794)
			(end -0.12065 -0.2794)
			(stroke
				(width 0.1)
				(type default)
			)
			(layer "B.Fab")
		)
		(fp_line
			(start 0.12065 -0.305054)
			(end 0.12065 -0.2794)
			(stroke
				(width 0.1)
				(type default)
			)
			(layer "B.Fab")
		)
		(fp_line
			(start -0.120396 0.3048)
			(end -0.120396 0.2794)
			(stroke
				(width 0.1)
				(type default)
			)
			(layer "B.Fab")
		)
		(fp_line
			(start -0.120396 0.2794)
			(end 0.12065 0.2794)
			(stroke
				(width 0.1)
				(type default)
			)
			(layer "B.Fab")
		)
		(fp_line
			(start -0.12065 -0.2794)
			(end -0.12065 -0.3048)
			(stroke
				(width 0.1)
				(type default)
			)
			(layer "B.Fab")
		)
		(fp_line
			(start -0.12065 -0.3048)
			(end -0.67945 -0.3048)
			(stroke
				(width 0.1)
				(type default)
			)
			(layer "B.Fab")
		)
		(fp_line
			(start -0.67945 0.3048)
			(end -0.120396 0.3048)
			(stroke
				(width 0.1)
				(type default)
			)
			(layer "B.Fab")
		)
		(fp_line
			(start -0.67945 -0.3048)
			(end -0.67945 0.3048)
			(stroke
				(width 0.1)
				(type default)
			)
			(layer "B.Fab")
		)
		(pad "1" smd circle
			(at 0.40005 0)
			(size 0 0)
			(layers "B.Cu" "B.Mask" "B.Paste")
			(net "OCP_V3_2_RBT_ARB_OUT")
		)
		(pad "2" smd circle
			(at -0.40005 0)
			(size 0 0)
			(layers "B.Cu" "B.Mask" "B.Paste")
			(net "OCP_V3_2_RBT_ARB_IN_R")
		)
	)
)
